(kicad_pcb
	(version 20260206)
	(generator "pcbnew")
	(generator_version "10.0")
	(general
		(thickness 1.6)
		(legacy_teardrops no)
	)
	(paper "A4")
	(title_block
		(title "baseboard — 13948-1b.1110WZS1818.brd")
		(comment 1 "Honey Badger (Wiwynn) / footprints 2181-2188 of 2523")
	)
	(layers
		(0 "F.Cu" signal "TOP")
		(4 "In1.Cu" signal "L2GND")
		(6 "In2.Cu" signal "L3")
		(8 "In3.Cu" signal "L4VCC")
		(10 "In4.Cu" signal "L5VCC")
		(12 "In5.Cu" signal "L6")
		(14 "In6.Cu" signal "L7GND")
		(2 "B.Cu" signal "BOTTOM")
		(9 "F.Adhes" user "F.Adhesive")
		(11 "B.Adhes" user "B.Adhesive")
		(13 "F.Paste" user "Package Geometry/Pastemask Top")
		(15 "B.Paste" user "Package Geometry/Pastemask Bottom")
		(5 "F.SilkS" user "Ref Des/Silkscreen Top")
		(7 "B.SilkS" user "Ref Des/Silkscreen Bottom")
		(1 "F.Mask" user "Board Geometry/Soldermask Top")
		(3 "B.Mask" user "Board Geometry/Soldermask Bottom")
		(17 "Dwgs.User" user "User.Drawings")
		(19 "Cmts.User" user "User.Comments")
		(21 "Eco1.User" user "User.Eco1")
		(23 "Eco2.User" user "User.Eco2")
		(25 "Edge.Cuts" user "Board Geometry/Outline")
		(27 "Margin" user)
		(31 "F.CrtYd" user "Package Geometry/Place Bound Top")
		(29 "B.CrtYd" user "Package Geometry/Place Bound Bottom")
		(35 "F.Fab" user "Ref Des/Assembly Top")
		(33 "B.Fab" user "Ref Des/Assembly Bottom")
	)
	(footprint ""
		(layer "B.Cu")
		(at 13.582904 -100.400866)
		(property "Reference" "C131"
			(at 0 0 0)
			(layer "B.SilkS")
			(hide yes)
			(effects
				(font
					(size 1.27 1.27)
				)
				(justify mirror)
			)
		)
		(property "Value" "SCD01U50V2KX-1GP"
			(at -1.1811 -2.7051 0)
			(unlocked yes)
			(layer "B.Fab")
			(hide yes)
			(effects
				(font
					(size 1.016 1.016)
					(thickness 0.1524)
				)
				(justify mirror)
			)
		)
		(property "Device Type" "C402H22"
			(at -1.1811 -4.2291 0)
			(unlocked yes)
			(layer "B.Fab")
			(hide yes)
			(effects
				(font
					(size 1.016 1.016)
					(thickness 0.1524)
				)
				(justify mirror)
			)
		)
		(duplicate_pad_numbers_are_jumpers no)
		(fp_rect
			(start 0.4318 0.9525)
			(end -0.4318 -0.9525)
			(stroke
				(width 0)
				(type default)
			)
			(fill no)
			(layer "B.CrtYd")
		)
		(fp_rect
			(start 0.4318 0.9525)
			(end -0.4318 -0.9525)
			(stroke
				(width 0)
				(type default)
			)
			(fill no)
			(layer "B.Fab")
		)
		(pad "1" smd custom
			(at 0 -0.4445 180)
			(size 0.1524 0.1524)
			(layers "B.Cu" "B.Mask" "B.Paste")
			(net "IOC_SAS_RX_P5")
			(options
				(clearance outline)
				(anchor circle)
			)
			(primitives
				(gr_poly
					(pts
						(arc
							(start 0.3048 0.2032)
							(mid 0.275042 0.275042)
							(end 0.2032 0.3048)
						)
						(arc
							(start -0.2032 0.3048)
							(mid -0.275042 0.275042)
							(end -0.3048 0.2032)
						)
						(arc
							(start -0.3048 -0.2032)
							(mid -0.275042 -0.275042)
							(end -0.2032 -0.3048)
						)
						(arc
							(start 0.2032 -0.3048)
							(mid 0.275042 -0.275042)
							(end 0.3048 -0.2032)
						)
					)
					(width 0)
					(fill yes)
				)
			)
		)
		(pad "2" smd custom
			(at 0 0.4445 180)
			(size 0.1524 0.1524)
			(layers "B.Cu" "B.Mask" "B.Paste")
			(net "SAS_EXT_CONN_RX17_P")
			(options
				(clearance outline)
				(anchor circle)
			)
			(primitives
				(gr_poly
					(pts
						(arc
							(start 0.3048 0.2032)
							(mid 0.275042 0.275042)
							(end 0.2032 0.3048)
						)
						(arc
							(start -0.2032 0.3048)
							(mid -0.275042 0.275042)
							(end -0.3048 0.2032)
						)
						(arc
							(start -0.3048 -0.2032)
							(mid -0.275042 -0.275042)
							(end -0.2032 -0.3048)
						)
						(arc
							(start 0.2032 -0.3048)
							(mid 0.275042 -0.275042)
							(end 0.3048 -0.2032)
						)
					)
					(width 0)
					(fill yes)
				)
			)
		)
	)
	(footprint ""
		(layer "B.Cu")
		(at 103.01097 -96.266)
		(property "Reference" "STP82"
			(at 0 0 0)
			(layer "B.SilkS")
			(hide yes)
			(effects
				(font
					(size 1.27 1.27)
				)
				(justify mirror)
			)
		)
		(property "Value" "TPAD28"
			(at -0.0127 -1.8034 0)
			(unlocked yes)
			(layer "B.Fab")
			(hide yes)
			(effects
				(font
					(size 1.016 1.016)
					(thickness 0.1524)
				)
				(justify mirror)
			)
		)
		(property "Device Type" "TPAD28"
			(at -0.0127 -3.3274 0)
			(unlocked yes)
			(layer "B.Fab")
			(hide yes)
			(effects
				(font
					(size 1.016 1.016)
					(thickness 0.1524)
				)
				(justify mirror)
			)
		)
		(duplicate_pad_numbers_are_jumpers no)
		(fp_poly
			(pts
				(arc
					(start 0.3556 0)
					(mid -0.3556 0)
					(end 0.3556 0)
				)
			)
			(stroke
				(width 0)
				(type default)
			)
			(fill no)
			(layer "B.CrtYd")
		)
		(fp_poly
			(pts
				(arc
					(start 0.6096 0)
					(mid -0.6096 0)
					(end 0.6096 0)
				)
			)
			(stroke
				(width 0)
				(type default)
			)
			(fill no)
			(layer "B.Fab")
		)
		(pad "1" smd circle
			(at 0 0 180)
			(size 0.7112 0.7112)
			(layers "B.Cu" "B.Mask" "B.Paste")
			(net "EXP_TACH_IN2")
		)
	)
	(footprint ""
		(layer "B.Cu")
		(at 16.960088 -208.789016 90)
		(property "Reference" "SC860"
			(at 0 0 90)
			(layer "B.SilkS")
			(hide yes)
			(effects
				(font
					(size 1.27 1.27)
				)
				(justify mirror)
			)
		)
		(property "Value" "SCD1U16V2KX-3GP"
			(at -1.1811 -2.7051 90)
			(unlocked yes)
			(layer "B.Fab")
			(hide yes)
			(effects
				(font
					(size 1.016 1.016)
					(thickness 0.1524)
				)
				(justify mirror)
			)
		)
		(property "Device Type" "C402H22"
			(at -1.1811 -4.2291 90)
			(unlocked yes)
			(layer "B.Fab")
			(hide yes)
			(effects
				(font
					(size 1.016 1.016)
					(thickness 0.1524)
				)
				(justify mirror)
			)
		)
		(duplicate_pad_numbers_are_jumpers no)
		(fp_rect
			(start 0.4318 0.9525)
			(end -0.4318 -0.9525)
			(stroke
				(width 0)
				(type default)
			)
			(fill no)
			(layer "B.CrtYd")
		)
		(fp_rect
			(start 0.4318 0.9525)
			(end -0.4318 -0.9525)
			(stroke
				(width 0)
				(type default)
			)
			(fill no)
			(layer "B.Fab")
		)
		(pad "1" smd custom
			(at 0 -0.4445 270)
			(size 0.1524 0.1524)
			(layers "B.Cu" "B.Mask" "B.Paste")
			(net "P1V8_E")
			(options
				(clearance outline)
				(anchor circle)
			)
			(primitives
				(gr_poly
					(pts
						(arc
							(start 0.3048 0.2032)
							(mid 0.275042 0.275042)
							(end 0.2032 0.3048)
						)
						(arc
							(start -0.2032 0.3048)
							(mid -0.275042 0.275042)
							(end -0.3048 0.2032)
						)
						(arc
							(start -0.3048 -0.2032)
							(mid -0.275042 -0.275042)
							(end -0.2032 -0.3048)
						)
						(arc
							(start 0.2032 -0.3048)
							(mid 0.275042 -0.275042)
							(end 0.3048 -0.2032)
						)
					)
					(width 0)
					(fill yes)
				)
			)
		)
		(pad "2" smd custom
			(at 0 0.4445 270)
			(size 0.1524 0.1524)
			(layers "B.Cu" "B.Mask" "B.Paste")
			(net "GND")
			(options
				(clearance outline)
				(anchor circle)
			)
			(primitives
				(gr_poly
					(pts
						(arc
							(start 0.3048 0.2032)
							(mid 0.275042 0.275042)
							(end 0.2032 0.3048)
						)
						(arc
							(start -0.2032 0.3048)
							(mid -0.275042 0.275042)
							(end -0.3048 0.2032)
						)
						(arc
							(start -0.3048 -0.2032)
							(mid -0.275042 -0.275042)
							(end -0.2032 -0.3048)
						)
						(arc
							(start 0.2032 -0.3048)
							(mid 0.275042 -0.275042)
							(end 0.3048 -0.2032)
						)
					)
					(width 0)
					(fill yes)
				)
			)
		)
	)
	(footprint ""
		(layer "B.Cu")
		(at 94.309946 -50.22596)
		(property "Reference" "SC1015"
			(at 0 0 0)
			(layer "B.SilkS")
			(hide yes)
			(effects
				(font
					(size 1.27 1.27)
				)
				(justify mirror)
			)
		)
		(property "Value" "SC1KP50V2KX-1GP"
			(at -1.1811 -2.7051 0)
			(unlocked yes)
			(layer "B.Fab")
			(hide yes)
			(effects
				(font
					(size 1.016 1.016)
					(thickness 0.1524)
				)
				(justify mirror)
			)
		)
		(property "Device Type" "C402H22"
			(at -1.1811 -4.2291 0)
			(unlocked yes)
			(layer "B.Fab")
			(hide yes)
			(effects
				(font
					(size 1.016 1.016)
					(thickness 0.1524)
				)
				(justify mirror)
			)
		)
		(duplicate_pad_numbers_are_jumpers no)
		(fp_rect
			(start 0.4318 0.9525)
			(end -0.4318 -0.9525)
			(stroke
				(width 0)
				(type default)
			)
			(fill no)
			(layer "B.CrtYd")
		)
		(fp_rect
			(start 0.4318 0.9525)
			(end -0.4318 -0.9525)
			(stroke
				(width 0)
				(type default)
			)
			(fill no)
			(layer "B.Fab")
		)
		(pad "1" smd custom
			(at 0 -0.4445 180)
			(size 0.1524 0.1524)
			(layers "B.Cu" "B.Mask" "B.Paste")
			(net "P1V8_C")
			(options
				(clearance outline)
				(anchor circle)
			)
			(primitives
				(gr_poly
					(pts
						(arc
							(start 0.3048 0.2032)
							(mid 0.275042 0.275042)
							(end 0.2032 0.3048)
						)
						(arc
							(start -0.2032 0.3048)
							(mid -0.275042 0.275042)
							(end -0.3048 0.2032)
						)
						(arc
							(start -0.3048 -0.2032)
							(mid -0.275042 -0.275042)
							(end -0.2032 -0.3048)
						)
						(arc
							(start 0.2032 -0.3048)
							(mid 0.275042 -0.275042)
							(end 0.3048 -0.2032)
						)
					)
					(width 0)
					(fill yes)
				)
			)
		)
		(pad "2" smd custom
			(at 0 0.4445 180)
			(size 0.1524 0.1524)
			(layers "B.Cu" "B.Mask" "B.Paste")
			(net "GND")
			(options
				(clearance outline)
				(anchor circle)
			)
			(primitives
				(gr_poly
					(pts
						(arc
							(start 0.3048 0.2032)
							(mid 0.275042 0.275042)
							(end 0.2032 0.3048)
						)
						(arc
							(start -0.2032 0.3048)
							(mid -0.275042 0.275042)
							(end -0.3048 0.2032)
						)
						(arc
							(start -0.3048 -0.2032)
							(mid -0.275042 -0.275042)
							(end -0.2032 -0.3048)
						)
						(arc
							(start 0.2032 -0.3048)
							(mid 0.275042 -0.275042)
							(end 0.3048 -0.2032)
						)
					)
					(width 0)
					(fill yes)
				)
			)
		)
	)
	(footprint ""
		(layer "B.Cu")
		(at 90.68816 -53.086)
		(property "Reference" "SR628"
			(at 0 0 0)
			(layer "B.SilkS")
			(hide yes)
			(effects
				(font
					(size 1.27 1.27)
				)
				(justify mirror)
			)
		)
		(property "Value" "2K2R2F-GP"
			(at -0.064008 -3.993896 0)
			(unlocked yes)
			(layer "B.Fab")
			(hide yes)
			(effects
				(font
					(size 1.016 1.016)
					(thickness 0.1524)
				)
				(justify mirror)
			)
		)
		(property "Device Type" "R402H16"
			(at -0.064008 -5.517896 0)
			(unlocked yes)
			(layer "B.Fab")
			(hide yes)
			(effects
				(font
					(size 1.016 1.016)
					(thickness 0.1524)
				)
				(justify mirror)
			)
		)
		(duplicate_pad_numbers_are_jumpers no)
		(fp_line
			(start -0.508 -0.9398)
			(end 0.508 -0.9398)
			(stroke
				(width 0.1524)
				(type default)
			)
			(layer "B.SilkS")
		)
		(fp_line
			(start 0.508 -0.9398)
			(end 0.508 0.9398)
			(stroke
				(width 0.1524)
				(type default)
			)
			(layer "B.SilkS")
		)
		(fp_rect
			(start 0.508 0.9398)
			(end -0.508 -0.9398)
			(stroke
				(width 0)
				(type default)
			)
			(fill no)
			(layer "B.CrtYd")
		)
		(fp_rect
			(start 0.508 0.9398)
			(end -0.508 -0.9398)
			(stroke
				(width 0)
				(type default)
			)
			(fill no)
			(layer "B.Fab")
		)
		(pad "1" smd custom
			(at 0 -0.4445 180)
			(size 0.1397 0.1397)
			(layers "B.Cu" "B.Mask" "B.Paste")
			(net "P1V8_C")
			(options
				(clearance outline)
				(anchor circle)
			)
			(primitives
				(gr_poly
					(pts
						(arc
							(start -0.1778 0.2794)
							(mid -0.249642 0.249642)
							(end -0.2794 0.1778)
						)
						(arc
							(start -0.2794 -0.1778)
							(mid -0.249642 -0.249642)
							(end -0.1778 -0.2794)
						)
						(arc
							(start 0.1778 -0.2794)
							(mid 0.249642 -0.249642)
							(end 0.2794 -0.1778)
						)
						(arc
							(start 0.2794 0.1778)
							(mid 0.249642 0.249642)
							(end 0.1778 0.2794)
						)
					)
					(width 0)
					(fill yes)
				)
			)
		)
		(pad "2" smd custom
			(at 0 0.4445 180)
			(size 0.1397 0.1397)
			(layers "B.Cu" "B.Mask" "B.Paste")
			(net "SIO_DOUT_0")
			(options
				(clearance outline)
				(anchor circle)
			)
			(primitives
				(gr_poly
					(pts
						(arc
							(start -0.1778 0.2794)
							(mid -0.249642 0.249642)
							(end -0.2794 0.1778)
						)
						(arc
							(start -0.2794 -0.1778)
							(mid -0.249642 -0.249642)
							(end -0.1778 -0.2794)
						)
						(arc
							(start 0.1778 -0.2794)
							(mid 0.249642 -0.249642)
							(end 0.2794 -0.1778)
						)
						(arc
							(start 0.2794 0.1778)
							(mid 0.249642 0.249642)
							(end 0.1778 0.2794)
						)
					)
					(width 0)
					(fill yes)
				)
			)
		)
	)
	(footprint ""
		(layer "B.Cu")
		(at 118.472966 -26.416 -90)
		(property "Reference" "SR652"
			(at 0 0 90)
			(layer "B.SilkS")
			(hide yes)
			(effects
				(font
					(size 1.27 1.27)
				)
				(justify mirror)
			)
		)
		(property "Value" "150R2F-1-GP"
			(at -0.064008 -3.993896 270)
			(unlocked yes)
			(layer "B.Fab")
			(hide yes)
			(effects
				(font
					(size 1.016 1.016)
					(thickness 0.1524)
				)
				(justify mirror)
			)
		)
		(property "Device Type" "R402H16"
			(at -0.064008 -5.517896 270)
			(unlocked yes)
			(layer "B.Fab")
			(hide yes)
			(effects
				(font
					(size 1.016 1.016)
					(thickness 0.1524)
				)
				(justify mirror)
			)
		)
		(duplicate_pad_numbers_are_jumpers no)
		(fp_line
			(start -0.508 -0.9398)
			(end 0.508 -0.9398)
			(stroke
				(width 0.1524)
				(type default)
			)
			(layer "B.SilkS")
		)
		(fp_line
			(start 0.508 -0.9398)
			(end 0.508 0.9398)
			(stroke
				(width 0.1524)
				(type default)
			)
			(layer "B.SilkS")
		)
		(fp_rect
			(start 0.508 0.9398)
			(end -0.508 -0.9398)
			(stroke
				(width 0)
				(type default)
			)
			(fill no)
			(layer "B.CrtYd")
		)
		(fp_rect
			(start 0.508 0.9398)
			(end -0.508 -0.9398)
			(stroke
				(width 0)
				(type default)
			)
			(fill no)
			(layer "B.Fab")
		)
		(pad "1" smd custom
			(at 0 -0.4445 90)
			(size 0.1397 0.1397)
			(layers "B.Cu" "B.Mask" "B.Paste")
			(net "P3V3")
			(options
				(clearance outline)
				(anchor circle)
			)
			(primitives
				(gr_poly
					(pts
						(arc
							(start -0.1778 0.2794)
							(mid -0.249642 0.249642)
							(end -0.2794 0.1778)
						)
						(arc
							(start -0.2794 -0.1778)
							(mid -0.249642 -0.249642)
							(end -0.1778 -0.2794)
						)
						(arc
							(start 0.1778 -0.2794)
							(mid 0.249642 -0.249642)
							(end 0.2794 -0.1778)
						)
						(arc
							(start 0.2794 0.1778)
							(mid 0.249642 0.249642)
							(end 0.1778 0.2794)
						)
					)
					(width 0)
					(fill yes)
				)
			)
		)
		(pad "2" smd custom
			(at 0 0.4445 90)
			(size 0.1397 0.1397)
			(layers "B.Cu" "B.Mask" "B.Paste")
			(net "SYS_ERROR_LED_R")
			(options
				(clearance outline)
				(anchor circle)
			)
			(primitives
				(gr_poly
					(pts
						(arc
							(start -0.1778 0.2794)
							(mid -0.249642 0.249642)
							(end -0.2794 0.1778)
						)
						(arc
							(start -0.2794 -0.1778)
							(mid -0.249642 -0.249642)
							(end -0.1778 -0.2794)
						)
						(arc
							(start 0.1778 -0.2794)
							(mid 0.249642 -0.249642)
							(end 0.2794 -0.1778)
						)
						(arc
							(start 0.2794 0.1778)
							(mid 0.249642 0.249642)
							(end 0.1778 0.2794)
						)
					)
					(width 0)
					(fill yes)
				)
			)
		)
	)
	(footprint ""
		(layer "B.Cu")
		(at 158.42996 -106.121454 90)
		(property "Reference" "SC1242"
			(at 0 0 90)
			(layer "B.SilkS")
			(hide yes)
			(effects
				(font
					(size 1.27 1.27)
				)
				(justify mirror)
			)
		)
		(property "Value" "SCD1U6D3V1KX-GP"
			(at 2.8321 -1.7399 90)
			(unlocked yes)
			(layer "B.Fab")
			(hide yes)
			(effects
				(font
					(size 1.016 1.016)
					(thickness 0.1524)
				)
				(justify mirror)
			)
		)
		(property "Device Type" "C0201H13"
			(at 2.8321 -3.2639 90)
			(unlocked yes)
			(layer "B.Fab")
			(hide yes)
			(effects
				(font
					(size 1.016 1.016)
					(thickness 0.1524)
				)
				(justify mirror)
			)
		)
		(duplicate_pad_numbers_are_jumpers no)
		(fp_rect
			(start 0.2794 0.6477)
			(end -0.2794 -0.6477)
			(stroke
				(width 0)
				(type default)
			)
			(fill no)
			(layer "B.CrtYd")
		)
		(fp_rect
			(start 0.2794 0.6477)
			(end -0.2794 -0.6477)
			(stroke
				(width 0)
				(type default)
			)
			(fill no)
			(layer "B.Fab")
		)
		(pad "1" smd custom
			(at 0 -0.2794 270)
			(size 0.0762 0.0762)
			(layers "B.Cu" "B.Mask" "B.Paste")
			(net "P0V9_E")
			(options
				(clearance outline)
				(anchor circle)
			)
			(primitives
				(gr_poly
					(pts
						(arc
							(start 0.1524 0.127)
							(mid 0.137521 0.162921)
							(end 0.1016 0.1778)
						)
						(arc
							(start -0.1016 0.1778)
							(mid -0.137521 0.162921)
							(end -0.1524 0.127)
						)
						(arc
							(start -0.1524 -0.127)
							(mid -0.137521 -0.162921)
							(end -0.1016 -0.1778)
						)
						(arc
							(start 0.1016 -0.1778)
							(mid 0.137521 -0.162921)
							(end 0.1524 -0.127)
						)
					)
					(width 0)
					(fill yes)
				)
			)
		)
		(pad "2" smd custom
			(at 0 0.2794 270)
			(size 0.0762 0.0762)
			(layers "B.Cu" "B.Mask" "B.Paste")
			(net "GND")
			(options
				(clearance outline)
				(anchor circle)
			)
			(primitives
				(gr_poly
					(pts
						(arc
							(start 0.1524 0.127)
							(mid 0.137521 0.162921)
							(end 0.1016 0.1778)
						)
						(arc
							(start -0.1016 0.1778)
							(mid -0.137521 0.162921)
							(end -0.1524 0.127)
						)
						(arc
							(start -0.1524 -0.127)
							(mid -0.137521 -0.162921)
							(end -0.1016 -0.1778)
						)
						(arc
							(start 0.1016 -0.1778)
							(mid 0.137521 -0.162921)
							(end 0.1524 -0.127)
						)
					)
					(width 0)
					(fill yes)
				)
			)
		)
	)
	(footprint ""
		(layer "B.Cu")
		(at 84.455 -18.161 180)
		(property "Reference" "PC215"
			(at 0 0 0)
			(layer "B.SilkS")
			(hide yes)
			(effects
				(font
					(size 1.27 1.27)
				)
				(justify mirror)
			)
		)
		(property "Value" "SC1U25V3KX-GP"
			(at 0 -2.8194 180)
			(unlocked yes)
			(layer "B.Fab")
			(hide yes)
			(effects
				(font
					(size 1.016 1.016)
					(thickness 0.1524)
				)
				(justify mirror)
			)
		)
		(property "Device Type" "C603H36"
			(at 0 -4.3434 180)
			(unlocked yes)
			(layer "B.Fab")
			(hide yes)
			(effects
				(font
					(size 1.016 1.016)
					(thickness 0.1524)
				)
				(justify mirror)
			)
		)
		(duplicate_pad_numbers_are_jumpers no)
		(fp_line
			(start -0.508 0)
			(end 0.508 0)
			(stroke
				(width 0.2032)
				(type default)
			)
			(layer "B.SilkS")
		)
		(fp_rect
			(start 0.5842 1.3335)
			(end -0.5842 -1.3335)
			(stroke
				(width 0)
				(type default)
			)
			(fill no)
			(layer "B.CrtYd")
		)
		(fp_rect
			(start 0.5842 1.3335)
			(end -0.5842 -1.3335)
			(stroke
				(width 0)
				(type default)
			)
			(fill no)
			(layer "B.Fab")
		)
		(pad "1" smd custom
			(at 0 -0.762)
			(size 0.2159 0.2159)
			(layers "B.Cu" "B.Mask" "B.Paste")
			(net "VT235_VDDL")
			(options
				(clearance outline)
				(anchor circle)
			)
			(primitives
				(gr_poly
					(pts
						(arc
							(start -0.3302 0.4318)
							(mid -0.402042 0.402042)
							(end -0.4318 0.3302)
						)
						(arc
							(start -0.4318 -0.3302)
							(mid -0.402042 -0.402042)
							(end -0.3302 -0.4318)
						)
						(arc
							(start 0.3302 -0.4318)
							(mid 0.402042 -0.402042)
							(end 0.4318 -0.3302)
						)
						(arc
							(start 0.4318 0.3302)
							(mid 0.402042 0.402042)
							(end 0.3302 0.4318)
						)
					)
					(width 0)
					(fill yes)
				)
			)
		)
		(pad "2" smd custom
			(at 0 0.762)
			(size 0.2159 0.2159)
			(layers "B.Cu" "B.Mask" "B.Paste")
			(net "AGND_P0V9_C")
			(options
				(clearance outline)
				(anchor circle)
			)
			(primitives
				(gr_poly
					(pts
						(arc
							(start -0.3302 0.4318)
							(mid -0.402042 0.402042)
							(end -0.4318 0.3302)
						)
						(arc
							(start -0.4318 -0.3302)
							(mid -0.402042 -0.402042)
							(end -0.3302 -0.4318)
						)
						(arc
							(start 0.3302 -0.4318)
							(mid 0.402042 -0.402042)
							(end 0.4318 -0.3302)
						)
						(arc
							(start 0.4318 0.3302)
							(mid 0.402042 0.402042)
							(end 0.3302 0.4318)
						)
					)
					(width 0)
					(fill yes)
				)
			)
		)
	)
)
